# BASEBOARD_FAB2 (Tioga Pass) — schematic parts with pin connectivity, parts 2376–2376 of 4751; source: Cadence DE-HDL packaged netlist (pstxprt.dat, pstxnet.dat, pstchip.dat)

J6T1  SCONN288_H44441003  SCONN  pkg PIP  page 44
  1  \12v\(1)  = P12V_NVDIMM_ABC
  2  VSS(93)  GROUND  = GND
  3  DQ(4)  BI  = M_A_DQ<4>
  4  VSS(92)  GROUND  = GND
  5  DQ(0)  BI  = M_A_DQ<0>
  6  VSS(91)  GROUND  = GND
  7  DQS9P  BI  = M_A_DQS_DP<9>
  8  DQS9N  BI  = M_A_DQS_DN<9>
  9  VSS(90)  GROUND  = GND
  10  DQ(6)  BI  = M_A_DQ<6>
  11  VSS(89)  GROUND  = GND
  12  DQ(2)  BI  = M_A_DQ<2>
  13  VSS(88)  GROUND  = GND
  14  DQ(12)  BI  = M_A_DQ<12>
  15  VSS(87)  GROUND  = GND
  16  DQ(8)  BI  = M_A_DQ<8>
  17  VSS(86)  GROUND  = GND
  18  DQS10P  BI  = M_A_DQS_DP<10>
  19  DQS10N  BI  = M_A_DQS_DN<10>
  20  VSS(85)  GROUND  = GND
  21  DQ(14)  BI  = M_A_DQ<14>
  22  VSS(84)  GROUND  = GND
  23  DQ(10)  BI  = M_A_DQ<10>
  24  VSS(83)  GROUND  = GND
  25  DQ(20)  BI  = M_A_DQ<20>
  26  VSS(82)  GROUND  = GND
  27  DQ(16)  BI  = M_A_DQ<16>
  28  VSS(81)  GROUND  = GND
  29  DQS11P  BI  = M_A_DQS_DP<11>
  30  DQS11N  BI  = M_A_DQS_DN<11>
  31  VSS(80)  GROUND  = GND
  32  DQ(22)  BI  = M_A_DQ<22>
  33  VSS(79)  GROUND  = GND
  34  DQ(18)  BI  = M_A_DQ<18>
  35  VSS(78)  GROUND  = GND
  36  DQ(28)  BI  = M_A_DQ<28>
  37  VSS(77)  GROUND  = GND
  38  DQ(24)  BI  = M_A_DQ<24>
  39  VSS(76)  GROUND  = GND
  40  DQS12P  BI  = M_A_DQS_DP<12>
  41  DQS12N  BI  = M_A_DQS_DN<12>
  42  VSS(75)  GROUND  = GND
  43  DQ(30)  BI  = M_A_DQ<30>
  44  VSS(74)  GROUND  = GND
  45  DQ(26)  BI  = M_A_DQ<26>
  46  VSS(73)  GROUND  = GND
  47  CB(4)  BI  = M_A_ECC<4>
  48  VSS(72)  GROUND  = GND
  49  CB(0)  BI  = M_A_ECC<0>
  50  VSS(71)  GROUND  = GND
  51  DQS17P  BI  = M_A_DQS_DP<17>
  52  DQS17N  BI  = M_A_DQS_DN<17>
  53  VSS(70)  GROUND  = GND
  54  CB(6)  BI  = M_A_ECC<6>
  55  VSS(69)  GROUND  = GND
  56  CB(2)  BI  = M_A_ECC<2>
  57  VSS(68)  GROUND  = GND
  58  RESET_N  BI  = M_ABC_RST_N
  59  VDD(25)  POWER  = PVDDQ_ABC
  60  CKE(0)  BI  = M_A_CKE<2>
  61  VDD(24)  POWER  = PVDDQ_ABC
  62  ACT_N  BI  = M_A_ACT_N
  63  BG(0)  BI  = M_A_BG<0>
  64  VDD(23)  POWER  = PVDDQ_ABC
  65  A12  BI  = M_A_MA<12>
  66  A9  BI  = M_A_MA<9>
  67  VDD(22)  POWER  = PVDDQ_ABC
  68  A8  BI  = M_A_MA<8>
  69  A6  BI  = M_A_MA<6>
  70  VDD(21)  POWER  = PVDDQ_ABC
  71  A3  BI  = M_A_MA<3>
  72  A1  BI  = M_A_MA<1>
  73  VDD(20)  POWER  = PVDDQ_ABC
  74  CK0P  BI  = M_A_CLK_DP<2>
  75  CK0N  BI  = M_A_CLK_DN<2>
  76  VDD(19)  POWER  = PVDDQ_ABC
  77  VTT(1)  POWER  = PVTT_ABC
  78  EVENT_N  BI  = FM_DIMM_EVENT_COD_N
  79  A0  BI  = M_A_MA<0>
  80  VDD(18)  POWER  = PVDDQ_ABC
  81  BA(0)  BI  = M_A_BA<0>
  82  A16_RAS_N  BI  = M_A_MA<16>
  83  VDD(17)  POWER  = PVDDQ_ABC
  84  S0_N  BI  = M_A_CS_N<4>
  85  VDD(16)  POWER  = PVDDQ_ABC
  86  A15_CAS_N  BI  = M_A_MA<15>
  87  ODT(0)  BI  = M_A_ODT<2>
  88  VDD(15)  POWER  = PVDDQ_ABC
  89  S1_N  BI  = M_A_CS_N<5>
  90  VDD(14)  POWER  = PVDDQ_ABC
  91  ODT(1)  BI  = M_A_ODT<3>
  92  VDD(13)  POWER  = PVDDQ_ABC
  93  S2_N_C(0)  BI  = M_A_CS_N<6>
  94  VSS(67)  GROUND  = GND
  95  DQ(36)  BI  = M_A_DQ<36>
  96  VSS(66)  GROUND  = GND
  97  DQ(32)  BI  = M_A_DQ<32>
  98  VSS(65)  GROUND  = GND
  99  DQS13P  BI  = M_A_DQS_DP<13>
  100  DQS13N  BI  = M_A_DQS_DN<13>
  101  VSS(64)  GROUND  = GND
  102  DQ(38)  BI  = M_A_DQ<38>
  103  VSS(63)  GROUND  = GND
  104  DQ(34)  BI  = M_A_DQ<34>
  105  VSS(62)  GROUND  = GND
  106  DQ(44)  BI  = M_A_DQ<44>
  107  VSS(61)  GROUND  = GND
  108  DQ(40)  BI  = M_A_DQ<40>
  109  VSS(60)  GROUND  = GND
  110  DQS14P  BI  = M_A_DQS_DP<14>
  111  DQS14N  BI  = M_A_DQS_DN<14>
  112  VSS(59)  GROUND  = GND
  113  DQ(46)  BI  = M_A_DQ<46>
  114  VSS(58)  GROUND  = GND
  115  DQ(42)  BI  = M_A_DQ<42>
  116  VSS(57)  GROUND  = GND
  117  DQ(52)  BI  = M_A_DQ<52>
  118  VSS(56)  GROUND  = GND
  119  DQ(48)  BI  = M_A_DQ<48>
  120  VSS(55)  GROUND  = GND
  121  DQS15P  BI  = M_A_DQS_DP<15>
  122  DQS15N  BI  = M_A_DQS_DN<15>
  123  VSS(54)  GROUND  = GND
  124  DQ(54)  BI  = M_A_DQ<54>
  125  VSS(53)  GROUND  = GND
  126  DQ(50)  BI  = M_A_DQ<50>
  127  VSS(52)  GROUND  = GND
  128  DQ(60)  BI  = M_A_DQ<60>
  129  VSS(51)  GROUND  = GND
  130  DQ(56)  BI  = M_A_DQ<56>
  131  VSS(50)  GROUND  = GND
  132  DQS16P  BI  = M_A_DQS_DP<16>
  133  DQS16N  BI  = M_A_DQS_DN<16>
  134  VSS(49)  GROUND  = GND
  135  DQ(62)  BI  = M_A_DQ<62>
  136  VSS(48)  GROUND  = GND
  137  DQ(58)  BI  = M_A_DQ<58>
  138  VSS(47)  GROUND  = GND
  139  SA(0)  BI  = PVPP_ABC
  140  SA(1)  BI  = GND
  141  SCL  BI  = SMB_DDR_ABC_VPP_SCL
  142  VPP(4)  POWER  = PVPP_ABC
  143  VPP(3)  POWER  = PVPP_ABC
  144  RFU(2)  BI  = TP_CH_A_DIMM_A1_RFU_2
  145  \12v\(0)  = P12V_NVDIMM_ABC
  146  VREFCA  BI  = M_A_VREF
  147  VSS(46)  GROUND  = GND
  148  DQ(5)  BI  = M_A_DQ<5>
  149  VSS(45)  GROUND  = GND
  150  DQ(1)  BI  = M_A_DQ<1>
  151  VSS(44)  GROUND  = GND
  152  DQS0N  BI  = M_A_DQS_DN<0>
  153  DQS0P  BI  = M_A_DQS_DP<0>
  154  VSS(43)  GROUND  = GND
  155  DQ(7)  BI  = M_A_DQ<7>
  156  VSS(42)  GROUND  = GND
  157  DQ(3)  BI  = M_A_DQ<3>
  158  VSS(41)  GROUND  = GND
  159  DQ(13)  BI  = M_A_DQ<13>
  160  VSS(40)  GROUND  = GND
  161  DQ(9)  BI  = M_A_DQ<9>
  162  VSS(39)  GROUND  = GND
  163  DQS1N  BI  = M_A_DQS_DN<1>
  164  DQS1P  BI  = M_A_DQS_DP<1>
  165  VSS(38)  GROUND  = GND
  166  DQ(15)  BI  = M_A_DQ<15>
  167  VSS(37)  GROUND  = GND
  168  DQ(11)  BI  = M_A_DQ<11>
  169  VSS(36)  GROUND  = GND
  170  DQ(21)  BI  = M_A_DQ<21>
  171  VSS(35)  GROUND  = GND
  172  DQ(17)  BI  = M_A_DQ<17>
  173  VSS(34)  GROUND  = GND
  174  DQS2N  BI  = M_A_DQS_DN<2>
  175  DQS2P  BI  = M_A_DQS_DP<2>
  176  VSS(33)  GROUND  = GND
  177  DQ(23)  BI  = M_A_DQ<23>
  178  VSS(32)  GROUND  = GND
  179  DQ(19)  BI  = M_A_DQ<19>
  180  VSS(31)  GROUND  = GND
  181  DQ(29)  BI  = M_A_DQ<29>
  182  VSS(30)  GROUND  = GND
  183  DQ(25)  BI  = M_A_DQ<25>
  184  VSS(29)  GROUND  = GND
  185  DQS3N  BI  = M_A_DQS_DN<3>
  186  DQS3P  BI  = M_A_DQS_DP<3>
  187  VSS(28)  GROUND  = GND
  188  DQ(31)  BI  = M_A_DQ<31>
  189  VSS(27)  GROUND  = GND
  190  DQ(27)  BI  = M_A_DQ<27>
  191  VSS(26)  GROUND  = GND
  192  CB(5)  BI  = M_A_ECC<5>
  193  VSS(25)  GROUND  = GND
  194  CB(1)  BI  = M_A_ECC<1>
  195  VSS(24)  GROUND  = GND
  196  DQS8N  BI  = M_A_DQS_DN<8>
  197  DQS8P  BI  = M_A_DQS_DP<8>
  198  VSS(23)  GROUND  = GND
  199  CB(7)  BI  = M_A_ECC<7>
  200  VSS(22)  GROUND  = GND
  201  CB(3)  BI  = M_A_ECC<3>
  202  VSS(21)  GROUND  = GND
  203  CKE(1)  BI  = M_A_CKE<3>
  204  VDD(12)  POWER  = PVDDQ_ABC
  205  RFU(0)  BI  = TP_CH_A_DIMM_A1_RFU_0
  206  VDD(11)  POWER  = PVDDQ_ABC
  207  BG(1)  BI  = M_A_BG<1>
  208  ALERT_N  BI  = M_A_ALERT_N
  209  VDD(10)  POWER  = PVDDQ_ABC
  210  A11  BI  = M_A_MA<11>
  211  A7  BI  = M_A_MA<7>
  212  VDD(9)  POWER  = PVDDQ_ABC
  213  A5  BI  = M_A_MA<5>
  214  A4  BI  = M_A_MA<4>
  215  VDD(8)  POWER  = PVDDQ_ABC
  216  A2  BI  = M_A_MA<2>
  217  VDD(7)  POWER  = PVDDQ_ABC
  218  CK1P  BI  = M_A_CLK_DP<3>
  219  CK1N  BI  = M_A_CLK_DN<3>
  220  VDD(6)  POWER  = PVDDQ_ABC
  221  VTT(0)  POWER  = PVTT_ABC
  222  PAR  BI  = M_A_PAR
  223  VDD(5)  POWER  = PVDDQ_ABC
  224  BA(1)  BI  = M_A_BA<1>
  225  A10  BI  = M_A_MA<10>
  226  VDD(4)  POWER  = PVDDQ_ABC
  227  RFU(1)  BI  = TP_CH_A_DIMM_A1_RFU_1
  228  A14_WE_N  BI  = M_A_MA<14>
  229  VDD(3)  POWER  = PVDDQ_ABC
  230  SAVE_N_NC  BI  = FM_ADR_COMPLETE_ABC_N
  231  VDD(2)  POWER  = PVDDQ_ABC
  232  A13  BI  = M_A_MA<13>
  233  VDD(1)  POWER  = PVDDQ_ABC
  234  A17  BI  = M_A_MA<17>
  235  C(2)  BI  = M_A_C<2>
  236  VDD(0)  POWER  = PVDDQ_ABC
  237  S3_N_C(1)  BI  = M_A_CS_N<7>
  238  SA(2)  BI  = GND
  239  VSS(20)  GROUND  = GND
  240  DQ(37)  BI  = M_A_DQ<37>
  241  VSS(19)  GROUND  = GND
  242  DQ(33)  BI  = M_A_DQ<33>
  243  VSS(18)  GROUND  = GND
  244  DQS4N  BI  = M_A_DQS_DN<4>
  245  DQS4P  BI  = M_A_DQS_DP<4>
  246  VSS(17)  GROUND  = GND
  247  DQ(39)  BI  = M_A_DQ<39>
  248  VSS(16)  GROUND  = GND
  249  DQ(35)  BI  = M_A_DQ<35>
  250  VSS(15)  GROUND  = GND
  251  DQ(45)  BI  = M_A_DQ<45>
  252  VSS(14)  GROUND  = GND
  253  DQ(41)  BI  = M_A_DQ<41>
  254  VSS(13)  GROUND  = GND
  255  DQS5N  BI  = M_A_DQS_DN<5>
  256  DQS5P  BI  = M_A_DQS_DP<5>
  257  VSS(12)  GROUND  = GND
  258  DQ(47)  BI  = M_A_DQ<47>
  259  VSS(11)  GROUND  = GND
  260  DQ(43)  BI  = M_A_DQ<43>
  261  VSS(10)  GROUND  = GND
  262  DQ(53)  BI  = M_A_DQ<53>
  263  VSS(9)  GROUND  = GND
  264  DQ(49)  BI  = M_A_DQ<49>
  265  VSS(8)  GROUND  = GND
  266  DQS6N  BI  = M_A_DQS_DN<6>
  267  DQS6P  BI  = M_A_DQS_DP<6>
  268  VSS(7)  GROUND  = GND
  269  DQ(55)  BI  = M_A_DQ<55>
  270  VSS(6)  GROUND  = GND
  271  DQ(51)  BI  = M_A_DQ<51>
  272  VSS(5)  GROUND  = GND
  273  DQ(61)  BI  = M_A_DQ<61>
  274  VSS(4)  GROUND  = GND
  275  DQ(57)  BI  = M_A_DQ<57>
  276  VSS(3)  GROUND  = GND
  277  DQS7N  BI  = M_A_DQS_DN<7>
  278  DQS7P  BI  = M_A_DQS_DP<7>
  279  VSS(2)  GROUND  = GND
  280  DQ(63)  BI  = M_A_DQ<63>
  281  VSS(1)  GROUND  = GND
  282  DQ(59)  BI  = M_A_DQ<59>
  283  VSS(0)  GROUND  = GND
  284  VDDSPD  BI  = PVPP_ABC
  285  SDA  BI  = SMB_DDR_ABC_VPP_SDA
  286  VPP(1)  POWER  = PVPP_ABC
  287  VPP(0)  POWER  = PVPP_ABC
  288  VPP(2)  POWER  = PVPP_ABC
